# T6G (Grand Teton) — schematic netlist excerpt (pin names and nets, part order shuffled) for the footprints in the layout excerpt that follows; sources: Cadence DE-HDL packaged netlist, KiCad conversion of 04192023_DAF0TMB3IC0_F0TG_MB_C_brd_V02_OCP.brd

C2272  Q_CAP  22UF 4V 20% X6S  pkg C0402  page 72 : A = PVDDCR_SOC_P1 ; B = GND
PC351_3  Q_CAP  22UF 16V 20% X6S  pkg C0805  page 216 : A = SW_P12V_AUX_PVDDCR_SOC_P1_FLT ; B = GND
R6239  Q_RES  10K 1% CHIP  pkg 0402LF  page 267 : A = P3V3_AUX ; B = HSC_D_OC

(kicad_pcb
	(version 20260206)
	(generator "pcbnew")
	(generator_version "10.0")
	(general
		(thickness 1.6)
		(legacy_teardrops no)
	)
	(paper "A4")
	(title_block
		(title "04192023_DAF0TMB3IC0_F0TG_MB_C_brd_V02_OCP.brd")
		(comment 1 "Grand Teton / footprints 7227-7229 of 8354")
	)
	(layers
		(0 "F.Cu" signal "TOP")
		(4 "In1.Cu" signal "GND")
		(6 "In2.Cu" signal "IN1")
		(8 "In3.Cu" signal "GND1")
		(10 "In4.Cu" signal "IN2")
		(12 "In5.Cu" signal "GND2")
		(14 "In6.Cu" signal "IN3")
		(16 "In7.Cu" signal "GND3")
		(18 "In8.Cu" signal "VCC")
		(20 "In9.Cu" signal "VCC1")
		(22 "In10.Cu" signal "GND4")
		(24 "In11.Cu" signal "IN4")
		(26 "In12.Cu" signal "GND5")
		(28 "In13.Cu" signal "IN5")
		(30 "In14.Cu" signal "GND6")
		(32 "In15.Cu" signal "IN6")
		(34 "In16.Cu" signal "GND7")
		(2 "B.Cu" signal "BOTTOM")
		(9 "F.Adhes" user "F.Adhesive")
		(11 "B.Adhes" user "B.Adhesive")
		(13 "F.Paste" user "Package Geometry/Pastemask Top")
		(15 "B.Paste" user "Package Geometry/Pastemask Bottom")
		(5 "F.SilkS" user "Ref Des/Silkscreen Top")
		(7 "B.SilkS" user "Ref Des/Silkscreen Bottom")
		(1 "F.Mask" user "Board Geometry/Soldermask Top")
		(3 "B.Mask" user "Board Geometry/Soldermask Bottom")
		(17 "Dwgs.User" user "User.Drawings")
		(19 "Cmts.User" user "User.Comments")
		(21 "Eco1.User" user "User.Eco1")
		(23 "Eco2.User" user "User.Eco2")
		(25 "Edge.Cuts" user "Board Geometry/Outline")
		(27 "Margin" user)
		(31 "F.CrtYd" user "Package Geometry/Place Bound Top")
		(29 "B.CrtYd" user "Package Geometry/Place Bound Bottom")
		(35 "F.Fab" user "Ref Des/Assembly Top")
		(33 "B.Fab" user "Ref Des/Assembly Bottom")
	)
	(footprint ""
		(layer "B.Cu")
		(at 175.507142 -421.216074 180)
		(property "Reference" "R6239"
			(at 0 0 0)
			(layer "B.SilkS")
			(hide yes)
			(effects
				(font
					(size 1.27 1.27)
				)
				(justify mirror)
			)
		)
		(property "Value" ""
			(at 0 0 0)
			(layer "B.Fab")
			(effects
				(font
					(size 1.27 1.27)
				)
				(justify mirror)
			)
		)
		(duplicate_pad_numbers_are_jumpers no)
		(fp_line
			(start 0.7874 0.4064)
			(end 0.7874 -0.4064)
			(stroke
				(width 0.1524)
				(type default)
			)
			(layer "B.SilkS")
		)
		(fp_line
			(start 0.7874 -0.4064)
			(end -0.7874 -0.4064)
			(stroke
				(width 0.1524)
				(type default)
			)
			(layer "B.SilkS")
		)
		(fp_line
			(start -0.7874 0.4064)
			(end 0.7874 0.4064)
			(stroke
				(width 0.1524)
				(type default)
			)
			(layer "B.SilkS")
		)
		(fp_line
			(start -0.7874 -0.4064)
			(end -0.7874 0.4064)
			(stroke
				(width 0.1524)
				(type default)
			)
			(layer "B.SilkS")
		)
		(fp_line
			(start 0.67945 0.3048)
			(end 0.67945 -0.305054)
			(stroke
				(width 0.1)
				(type default)
			)
			(layer "B.Fab")
		)
		(fp_line
			(start 0.67945 -0.305054)
			(end 0.12065 -0.305054)
			(stroke
				(width 0.1)
				(type default)
			)
			(layer "B.Fab")
		)
		(fp_line
			(start 0.12065 0.3048)
			(end 0.67945 0.3048)
			(stroke
				(width 0.1)
				(type default)
			)
			(layer "B.Fab")
		)
		(fp_line
			(start 0.12065 0.2794)
			(end 0.12065 0.3048)
			(stroke
				(width 0.1)
				(type default)
			)
			(layer "B.Fab")
		)
		(fp_line
			(start 0.12065 -0.2794)
			(end -0.12065 -0.2794)
			(stroke
				(width 0.1)
				(type default)
			)
			(layer "B.Fab")
		)
		(fp_line
			(start 0.12065 -0.305054)
			(end 0.12065 -0.2794)
			(stroke
				(width 0.1)
				(type default)
			)
			(layer "B.Fab")
		)
		(fp_line
			(start -0.120396 0.3048)
			(end -0.120396 0.2794)
			(stroke
				(width 0.1)
				(type default)
			)
			(layer "B.Fab")
		)
		(fp_line
			(start -0.120396 0.2794)
			(end 0.12065 0.2794)
			(stroke
				(width 0.1)
				(type default)
			)
			(layer "B.Fab")
		)
		(fp_line
			(start -0.12065 -0.2794)
			(end -0.12065 -0.3048)
			(stroke
				(width 0.1)
				(type default)
			)
			(layer "B.Fab")
		)
		(fp_line
			(start -0.12065 -0.3048)
			(end -0.67945 -0.3048)
			(stroke
				(width 0.1)
				(type default)
			)
			(layer "B.Fab")
		)
		(fp_line
			(start -0.67945 0.3048)
			(end -0.120396 0.3048)
			(stroke
				(width 0.1)
				(type default)
			)
			(layer "B.Fab")
		)
		(fp_line
			(start -0.67945 -0.3048)
			(end -0.67945 0.3048)
			(stroke
				(width 0.1)
				(type default)
			)
			(layer "B.Fab")
		)
		(pad "1" smd circle
			(at 0.40005 0)
			(size 0 0)
			(layers "B.Cu" "B.Mask" "B.Paste")
			(net "P3V3_AUX")
		)
		(pad "2" smd circle
			(at -0.40005 0)
			(size 0 0)
			(layers "B.Cu" "B.Mask" "B.Paste")
			(net "HSC_D_OC")
		)
	)
	(footprint ""
		(layer "B.Cu")
		(at 129.289048 -156.393134 -90)
		(property "Reference" "PC351_3"
			(at 0 0 90)
			(layer "B.SilkS")
			(hide yes)
			(effects
				(font
					(size 1.27 1.27)
				)
				(justify mirror)
			)
		)
		(property "Value" ""
			(at 0 0 90)
			(layer "B.Fab")
			(effects
				(font
					(size 1.27 1.27)
				)
				(justify mirror)
			)
		)
		(duplicate_pad_numbers_are_jumpers no)
		(fp_line
			(start -1.524 0.762)
			(end 1.524 0.762)
			(stroke
				(width 0.1524)
				(type default)
			)
			(layer "B.SilkS")
		)
		(fp_line
			(start 1.524 0.762)
			(end 1.524 -0.762)
			(stroke
				(width 0.1524)
				(type default)
			)
			(layer "B.SilkS")
		)
		(fp_line
			(start -1.524 -0.762)
			(end -1.524 0.762)
			(stroke
				(width 0.1524)
				(type default)
			)
			(layer "B.SilkS")
		)
		(fp_line
			(start 1.524 -0.762)
			(end -1.524 -0.762)
			(stroke
				(width 0.1524)
				(type default)
			)
			(layer "B.SilkS")
		)
		(fp_line
			(start -1.1049 0.724916)
			(end -1.1049 -0.724916)
			(stroke
				(width 0.1)
				(type default)
			)
			(layer "B.Fab")
		)
		(fp_line
			(start 1.1049 0.724916)
			(end -1.1049 0.724916)
			(stroke
				(width 0.1)
				(type default)
			)
			(layer "B.Fab")
		)
		(fp_line
			(start -1.1049 -0.724916)
			(end 1.1049 -0.724916)
			(stroke
				(width 0.1)
				(type default)
			)
			(layer "B.Fab")
		)
		(fp_line
			(start 1.1049 -0.724916)
			(end 1.1049 0.724916)
			(stroke
				(width 0.1)
				(type default)
			)
			(layer "B.Fab")
		)
		(pad "1" smd rect
			(at 0.889 0 270)
			(size 1.016 1.27)
			(layers "B.Cu" "B.Mask" "B.Paste")
			(net "SW_P12V_AUX_PVDDCR_SOC_P1_FLT")
		)
		(pad "2" smd rect
			(at -0.889 0 270)
			(size 1.016 1.27)
			(layers "B.Cu" "B.Mask" "B.Paste")
			(net "GND")
		)
	)
	(footprint ""
		(layer "B.Cu")
		(at 111.781336 -253.432564 180)
		(property "Reference" "C2272"
			(at 0 0 0)
			(layer "B.SilkS")
			(hide yes)
			(effects
				(font
					(size 1.27 1.27)
				)
				(justify mirror)
			)
		)
		(property "Value" ""
			(at 0 0 0)
			(layer "B.Fab")
			(effects
				(font
					(size 1.27 1.27)
				)
				(justify mirror)
			)
		)
		(duplicate_pad_numbers_are_jumpers no)
		(fp_line
			(start 0.7874 0.4064)
			(end 0.7874 -0.4064)
			(stroke
				(width 0.1524)
				(type default)
			)
			(layer "B.SilkS")
		)
		(fp_line
			(start 0.7874 -0.4064)
			(end -0.7874 -0.4064)
			(stroke
				(width 0.1524)
				(type default)
			)
			(layer "B.SilkS")
		)
		(fp_line
			(start -0.7874 0.4064)
			(end 0.7874 0.4064)
			(stroke
				(width 0.1524)
				(type default)
			)
			(layer "B.SilkS")
		)
		(fp_line
			(start -0.7874 -0.4064)
			(end -0.7874 0.4064)
			(stroke
				(width 0.1524)
				(type default)
			)
			(layer "B.SilkS")
		)
		(fp_line
			(start 0.67945 0.3048)
			(end 0.67945 -0.305054)
			(stroke
				(width 0.1)
				(type default)
			)
			(layer "B.Fab")
		)
		(fp_line
			(start 0.67945 -0.305054)
			(end 0.12065 -0.305054)
			(stroke
				(width 0.1)
				(type default)
			)
			(layer "B.Fab")
		)
		(fp_line
			(start 0.12065 0.3048)
			(end 0.67945 0.3048)
			(stroke
				(width 0.1)
				(type default)
			)
			(layer "B.Fab")
		)
		(fp_line
			(start 0.12065 0.2794)
			(end 0.12065 0.3048)
			(stroke
				(width 0.1)
				(type default)
			)
			(layer "B.Fab")
		)
		(fp_line
			(start 0.12065 -0.2794)
			(end -0.12065 -0.2794)
			(stroke
				(width 0.1)
				(type default)
			)
			(layer "B.Fab")
		)
		(fp_line
			(start 0.12065 -0.305054)
			(end 0.12065 -0.2794)
			(stroke
				(width 0.1)
				(type default)
			)
			(layer "B.Fab")
		)
		(fp_line
			(start -0.120396 0.3048)
			(end -0.120396 0.2794)
			(stroke
				(width 0.1)
				(type default)
			)
			(layer "B.Fab")
		)
		(fp_line
			(start -0.120396 0.2794)
			(end 0.12065 0.2794)
			(stroke
				(width 0.1)
				(type default)
			)
			(layer "B.Fab")
		)
		(fp_line
			(start -0.12065 -0.2794)
			(end -0.12065 -0.3048)
			(stroke
				(width 0.1)
				(type default)
			)
			(layer "B.Fab")
		)
		(fp_line
			(start -0.12065 -0.3048)
			(end -0.67945 -0.3048)
			(stroke
				(width 0.1)
				(type default)
			)
			(layer "B.Fab")
		)
		(fp_line
			(start -0.67945 0.3048)
			(end -0.120396 0.3048)
			(stroke
				(width 0.1)
				(type default)
			)
			(layer "B.Fab")
		)
		(fp_line
			(start -0.67945 -0.3048)
			(end -0.67945 0.3048)
			(stroke
				(width 0.1)
				(type default)
			)
			(layer "B.Fab")
		)
		(pad "1" smd circle
			(at 0.40005 0)
			(size 0 0)
			(layers "B.Cu" "B.Mask" "B.Paste")
			(net "PVDDCR_SOC_P1")
		)
		(pad "2" smd circle
			(at -0.40005 0)
			(size 0 0)
			(layers "B.Cu" "B.Mask" "B.Paste")
			(net "GND")
		)
	)
)
